(kicad_pcb
	(version 20241229)
	(generator "pcbnew")
	(generator_version "9.0")
	(general
		(thickness 1.63)
		(legacy_teardrops no)
	)
	(paper "A4")
	(title_block
		(title "CM4 Baseboard")
		(date "2026-01-05")
		(rev "1.1.1")
		(company "Antmicro Ltd")
		(comment 1 "www.antmicro.com")
		(comment 9 "footprints 127-128 of 506")
	)
	(layers
		(0 "F.Cu" signal)
		(4 "In1.Cu" power)
		(6 "In2.Cu" power)
		(8 "In3.Cu" signal)
		(10 "In4.Cu" signal)
		(2 "B.Cu" signal)
		(9 "F.Adhes" user "F.Adhesive")
		(11 "B.Adhes" user "B.Adhesive")
		(13 "F.Paste" user)
		(15 "B.Paste" user)
		(5 "F.SilkS" user "F.Silkscreen")
		(7 "B.SilkS" user "B.Silkscreen")
		(1 "F.Mask" user)
		(3 "B.Mask" user)
		(17 "Dwgs.User" user "User.Drawings")
		(19 "Cmts.User" user "User.Comments")
		(21 "Eco1.User" user "User.Eco1")
		(23 "Eco2.User" user "User.Eco2")
		(25 "Edge.Cuts" user)
		(27 "Margin" user)
		(31 "F.CrtYd" user "F.Courtyard")
		(29 "B.CrtYd" user "B.Courtyard")
		(35 "F.Fab" user)
		(33 "B.Fab" user)
	)
	(footprint "antmicro-footprints:DHVQFN-14-1EP_2.5x3mm"
		(layer "F.Cu")
		(at 96.717962 145.2665)
		(property "Reference" "U904"
			(at 2.8 -0.2 90)
			(layer "F.SilkS")
			(effects
				(font
					(size 0.7 0.7)
					(thickness 0.15)
				)
				(justify left bottom)
			)
		)
		(property "Value" "NTS0104_DHVQFN"
			(at 0 2.898 0)
			(layer "F.Fab")
			(effects
				(font
					(size 0.7 0.7)
					(thickness 0.15)
				)
				(justify left bottom)
			)
		)
		(property "Datasheet" "https://www.nxp.com/docs/en/data-sheet/NTS0104.pdf"
			(at 0 0 0)
			(layer "F.Fab")
			(hide yes)
			(effects
				(font
					(size 1.27 1.27)
					(thickness 0.15)
				)
			)
		)
		(property "MPN" "NTS0104BQ"
			(at 0 0 0)
			(unlocked yes)
			(layer "F.Fab")
			(hide yes)
			(effects
				(font
					(size 1 1)
					(thickness 0.15)
				)
			)
		)
		(property "Manufacturer" "NXP"
			(at 0 0 0)
			(unlocked yes)
			(layer "F.Fab")
			(hide yes)
			(effects
				(font
					(size 1 1)
					(thickness 0.15)
				)
			)
		)
		(property "Author" "Antmicro"
			(at 0 0 0)
			(unlocked yes)
			(layer "F.Fab")
			(hide yes)
			(effects
				(font
					(size 1 1)
					(thickness 0.15)
				)
			)
		)
		(property "License" "Apache-2.0"
			(at 0 0 0)
			(unlocked yes)
			(layer "F.Fab")
			(hide yes)
			(effects
				(font
					(size 1 1)
					(thickness 0.15)
				)
			)
		)
		(sheetname "/USB/")
		(sheetfile "usb.kicad_sch")
		(attr smd)
		(fp_line
			(start -1.351 -1.601)
			(end -0.5 -1.601)
			(stroke
				(width 0.15)
				(type solid)
			)
			(layer "F.SilkS")
		)
		(fp_line
			(start -1.351 1.6)
			(end -1.351 1.249)
			(stroke
				(width 0.15)
				(type solid)
			)
			(layer "F.SilkS")
		)
		(fp_line
			(start -1.351 1.6)
			(end -0.5 1.6)
			(stroke
				(width 0.15)
				(type solid)
			)
			(layer "F.SilkS")
		)
		(fp_line
			(start -1.35 -1.601)
			(end -1.35 -1.25)
			(stroke
				(width 0.15)
				(type solid)
			)
			(layer "F.SilkS")
		)
		(fp_line
			(start 0.494 1.6)
			(end 1.35 1.6)
			(stroke
				(width 0.15)
				(type solid)
			)
			(layer "F.SilkS")
		)
		(fp_line
			(start 1.35 -1.601)
			(end 0.494 -1.601)
			(stroke
				(width 0.15)
				(type solid)
			)
			(layer "F.SilkS")
		)
		(fp_line
			(start 1.35 -1.601)
			(end 1.35 -1.25)
			(stroke
				(width 0.15)
				(type solid)
			)
			(layer "F.SilkS")
		)
		(fp_line
			(start 1.35 1.6)
			(end 1.35 1.249)
			(stroke
				(width 0.15)
				(type solid)
			)
			(layer "F.SilkS")
		)
		(fp_circle
			(center -0.7 -1.85)
			(end -0.653 -1.85)
			(stroke
				(width 0.15)
				(type solid)
			)
			(fill yes)
			(layer "F.SilkS")
		)
		(fp_rect
			(start -1.85 -2)
			(end 1.8 1.95)
			(stroke
				(width 0.05)
				(type solid)
			)
			(fill no)
			(layer "F.CrtYd")
		)
		(fp_line
			(start -1.25 -1.25)
			(end -1 -1.5)
			(stroke
				(width 0.15)
				(type solid)
			)
			(layer "F.Fab")
		)
		(fp_line
			(start -1.25 1.499)
			(end -1.25 -1.25)
			(stroke
				(width 0.15)
				(type solid)
			)
			(layer "F.Fab")
		)
		(fp_line
			(start -1 -1.5)
			(end 1.249 -1.5)
			(stroke
				(width 0.15)
				(type solid)
			)
			(layer "F.Fab")
		)
		(fp_line
			(start 1.249 -1.5)
			(end 1.249 1.499)
			(stroke
				(width 0.15)
				(type solid)
			)
			(layer "F.Fab")
		)
		(fp_line
			(start 1.249 1.499)
			(end -1.25 1.499)
			(stroke
				(width 0.15)
				(type solid)
			)
			(layer "F.Fab")
		)
		(fp_text user "Author: Antmicro"
			(at -1.841 7.296 0)
			(layer "F.Fab")
			(effects
				(font
					(size 0.7 0.7)
					(thickness 0.15)
				)
				(justify left bottom)
			)
		)
		(fp_text user "${REFERENCE}"
			(at -1.841 4.897 0)
			(layer "F.Fab")
			(effects
				(font
					(size 0.7 0.7)
					(thickness 0.15)
				)
				(justify left bottom)
			)
		)
		(fp_text user "License: Apache-2.0"
			(at -1.841 6.097 0)
			(layer "F.Fab")
			(effects
				(font
					(size 0.7 0.7)
					(thickness 0.15)
				)
				(justify left bottom)
			)
		)
		(pad "1" smd oval
			(at -0.25 -1.5)
			(size 0.3 0.8)
			(layers "F.Cu" "F.Mask" "F.Paste")
			(net 27 "/USB/USB_3V3")
			(pinfunction "VCC_A")
			(pintype "power_in")
		)
		(pad "2" smd oval
			(at -1.25 -1 90)
			(size 0.3 0.8)
			(layers "F.Cu" "F.Mask" "F.Paste")
			(net 456 "/USB/BDBUS0")
			(pinfunction "A1")
			(pintype "passive")
		)
		(pad "3" smd oval
			(at -1.25 -0.5 90)
			(size 0.3 0.8)
			(layers "F.Cu" "F.Mask" "F.Paste")
			(net 457 "/USB/BDBUS1")
			(pinfunction "A2")
			(pintype "passive")
		)
		(pad "4" smd oval
			(at -1.25 0 90)
			(size 0.3 0.8)
			(layers "F.Cu" "F.Mask" "F.Paste")
			(net 458 "/USB/BDBUS2")
			(pinfunction "A3")
			(pintype "passive")
		)
		(pad "5" smd oval
			(at -1.25 0.494 90)
			(size 0.3 0.8)
			(layers "F.Cu" "F.Mask" "F.Paste")
			(net 459 "unconnected-(U904-A4-Pad5)")
			(pinfunction "A4")
			(pintype "passive+no_connect")
		)
		(pad "6" smd oval
			(at -1.25 0.994 90)
			(size 0.3 0.8)
			(layers "F.Cu" "F.Mask" "F.Paste")
			(net 460 "unconnected-(U904-NC-Pad6)")
			(pinfunction "NC")
			(pintype "no_connect")
		)
		(pad "7" smd oval
			(at -0.25 1.499)
			(size 0.3 0.8)
			(layers "F.Cu" "F.Mask" "F.Paste")
			(net 3 "GND")
			(pinfunction "GND")
			(pintype "power_in")
		)
		(pad "8" smd oval
			(at 0.244 1.499)
			(size 0.3 0.8)
			(layers "F.Cu" "F.Mask" "F.Paste")
			(net 490 "Net-(Q905-G)")
			(pinfunction "OE")
			(pintype "passive")
		)
		(pad "9" smd oval
			(at 1.249 0.994 90)
			(size 0.3 0.8)
			(layers "F.Cu" "F.Mask" "F.Paste")
			(net 461 "unconnected-(U904-NC-Pad9)")
			(pinfunction "NC")
			(pintype "no_connect")
		)
		(pad "10" smd oval
			(at 1.249 0.494 90)
			(size 0.3 0.8)
			(layers "F.Cu" "F.Mask" "F.Paste")
			(net 462 "unconnected-(U904-B4-Pad10)")
			(pinfunction "B4")
			(pintype "passive+no_connect")
		)
		(pad "11" smd oval
			(at 1.249 0 90)
			(size 0.3 0.8)
			(layers "F.Cu" "F.Mask" "F.Paste")
			(net 143 "/CSI/I_{2}C1.SDA")
			(pinfunction "B3")
			(pintype "passive")
		)
		(pad "12" smd oval
			(at 1.249 -0.5 90)
			(size 0.3 0.8)
			(layers "F.Cu" "F.Mask" "F.Paste")
			(net 485 "Net-(D908-C)")
			(pinfunction "B2")
			(pintype "passive")
		)
		(pad "13" smd oval
			(at 1.249 -1 90)
			(size 0.3 0.8)
			(layers "F.Cu" "F.Mask" "F.Paste")
			(net 142 "/CSI/I_{2}C1.SCL")
			(pinfunction "B1")
			(pintype "passive")
		)
		(pad "14" smd oval
			(at 0.244 -1.5)
			(size 0.3 0.8)
			(layers "F.Cu" "F.Mask" "F.Paste")
			(net 9 "+3V3")
			(pinfunction "VCC_B")
			(pintype "power_in")
		)
		(pad "15" smd rect
			(at 0 0)
			(size 1 1.5)
			(layers "F.Cu" "F.Mask" "F.Paste")
			(net 3 "GND")
			(pinfunction "GNDPAD")
			(pintype "power_in")
		)
	)
	(footprint "antmicro-footprints:VQFN-20_5x5x1mm_P0.65mm"
		(layer "F.Cu")
		(at 50.561962 131.4165 -90)
		(property "Reference" "U401"
			(at 1.7535 3.551962 90)
			(layer "F.SilkS")
			(effects
				(font
					(size 0.7 0.7)
					(thickness 0.15)
				)
				(justify right bottom)
			)
		)
		(property "Value" "TPS2372-3RGWR"
			(at 0 3.883 90)
			(layer "F.Fab")
			(effects
				(font
					(size 0.7 0.7)
					(thickness 0.15)
				)
				(justify right bottom)
			)
		)
		(property "Datasheet" "https://www.ti.com/lit/ds/symlink/tps2372.pdf?ts=1679042478513&ref_url=https%253A%252F%252Fwww.google.com%252F"
			(at 0 0 270)
			(layer "F.Fab")
			(hide yes)
			(effects
				(font
					(size 1.27 1.27)
					(thickness 0.15)
				)
			)
		)
		(property "MPN" "TPS2372-3RGWR"
			(at 0 0 270)
			(unlocked yes)
			(layer "F.Fab")
			(hide yes)
			(effects
				(font
					(size 1 1)
					(thickness 0.15)
				)
			)
		)
		(property "Manufacturer" "Texas Instruments"
			(at 0 0 270)
			(unlocked yes)
			(layer "F.Fab")
			(hide yes)
			(effects
				(font
					(size 1 1)
					(thickness 0.15)
				)
			)
		)
		(property "Author" "Antmicro"
			(at 0 0 270)
			(unlocked yes)
			(layer "F.Fab")
			(hide yes)
			(effects
				(font
					(size 1 1)
					(thickness 0.15)
				)
			)
		)
		(property "License" "Apache-2.0"
			(at 0 0 270)
			(unlocked yes)
			(layer "F.Fab")
			(hide yes)
			(effects
				(font
					(size 1 1)
					(thickness 0.15)
				)
			)
		)
		(sheetname "/Ethernet/")
		(sheetfile "ethernet.kicad_sch")
		(attr smd)
		(fp_line
			(start -2.5 2.499)
			(end -1.79 2.499)
			(stroke
				(width 0.15)
				(type solid)
			)
			(layer "F.SilkS")
		)
		(fp_line
			(start -2.5 2.499)
			(end -2.5 1.789)
			(stroke
				(width 0.15)
				(type solid)
			)
			(layer "F.SilkS")
		)
		(fp_line
			(start 2.499 2.499)
			(end 1.789 2.499)
			(stroke
				(width 0.15)
				(type solid)
			)
			(layer "F.SilkS")
		)
		(fp_line
			(start 2.499 2.499)
			(end 2.499 1.789)
			(stroke
				(width 0.15)
				(type solid)
			)
			(layer "F.SilkS")
		)
		(fp_line
			(start -1.625 -2.5)
			(end -2.5 -2.5)
			(stroke
				(width 0.15)
				(type solid)
			)
			(layer "F.SilkS")
		)
		(fp_line
			(start 2.499 -2.5)
			(end 2.499 -1.79)
			(stroke
				(width 0.15)
				(type solid)
			)
			(layer "F.SilkS")
		)
		(fp_line
			(start 2.499 -2.5)
			(end 1.789 -2.5)
			(stroke
				(width 0.15)
				(type solid)
			)
			(layer "F.SilkS")
		)
		(fp_circle
			(center -2.775 -1.875)
			(end -2.725 -1.825)
			(stroke
				(width 0.15)
				(type solid)
			)
			(fill yes)
			(layer "F.SilkS")
		)
		(fp_poly
			(pts
				(xy -1.081 0.088) (xy -0.11 0.088) (xy -0.11 1.08) (xy -1.081 1.08)
			)
			(stroke
				(width 0.01)
				(type solid)
			)
			(fill yes)
			(layer "F.Paste")
		)
		(fp_poly
			(pts
				(xy 0.108 0.088) (xy 1.08 0.088) (xy 1.08 1.08) (xy 0.108 1.08)
			)
			(stroke
				(width 0.01)
				(type solid)
			)
			(fill yes)
			(layer "F.Paste")
		)
		(fp_poly
			(pts
				(xy -1.081 -1.081) (xy -0.11 -1.081) (xy -0.11 -0.09) (xy -1.081 -0.09)
			)
			(stroke
				(width 0.01)
				(type solid)
			)
			(fill yes)
			(layer "F.Paste")
		)
		(fp_poly
			(pts
				(xy 0.108 -1.081) (xy 1.08 -1.081) (xy 1.08 -0.09) (xy 0.108 -0.09)
			)
			(stroke
				(width 0.01)
				(type solid)
			)
			(fill yes)
			(layer "F.Paste")
		)
		(fp_rect
			(start -2.95 -2.95)
			(end 2.95 2.95)
			(stroke
				(width 0.05)
				(type solid)
			)
			(fill no)
			(layer "F.CrtYd")
		)
		(fp_line
			(start -2.5 2.499)
			(end -2.5 -1.65)
			(stroke
				(width 0.15)
				(type solid)
			)
			(layer "F.Fab")
		)
		(fp_line
			(start 2.499 2.499)
			(end -2.5 2.499)
			(stroke
				(width 0.15)
				(type solid)
			)
			(layer "F.Fab")
		)
		(fp_line
			(start 2.499 2.499)
			(end 2.499 -2.5)
			(stroke
				(width 0.15)
				(type solid)
			)
			(layer "F.Fab")
		)
		(fp_line
			(start -2.5 -1.65)
			(end -1.65 -2.5)
			(stroke
				(width 0.15)
				(type solid)
			)
			(layer "F.Fab")
		)
		(fp_line
			(start 2.499 -2.5)
			(end -1.65 -2.5)
			(stroke
				(width 0.15)
				(type solid)
			)
			(layer "F.Fab")
		)
		(fp_text user "Author: Antmicro"
			(at -2.5 6.884 270)
			(layer "F.Fab")
			(effects
				(font
					(size 0.7 0.7)
					(thickness 0.15)
				)
				(justify left bottom)
			)
		)
		(fp_text user "${REFERENCE}"
			(at -2.5 5.884 270)
			(layer "F.Fab")
			(effects
				(font
					(size 0.7 0.7)
					(thickness 0.15)
				)
				(justify left bottom)
			)
		)
		(fp_text user "License: Apache-2.0"
			(at -2.5 7.884 270)
			(layer "F.Fab")
			(effects
				(font
					(size 0.7 0.7)
					(thickness 0.15)
				)
				(justify left bottom)
			)
		)
		(pad "1" smd roundrect
			(at -2.327 -1.301 270)
			(size 0.75 0.31)
			(layers "F.Cu" "F.Mask" "F.Paste")
			(roundrect_rratio 0.25)
			(net 33 "/Ethernet/VDD")
			(pinfunction "VDD")
			(pintype "power_in")
		)
		(pad "2" smd roundrect
			(at -2.327 -0.652 270)
			(size 0.75 0.31)
			(layers "F.Cu" "F.Mask" "F.Paste")
			(roundrect_rratio 0.25)
			(net 361 "/Ethernet/DEN")
			(pinfunction "DEN")
			(pintype "input")
		)
		(pad "3" smd roundrect
			(at -2.327 0 270)
			(size 0.75 0.31)
			(layers "F.Cu" "F.Mask" "F.Paste")
			(roundrect_rratio 0.25)
			(net 359 "/Ethernet/CLSA")
			(pinfunction "CLSA")
			(pintype "input")
		)
		(pad "4" smd roundrect
			(at -2.327 0.65 270)
			(size 0.75 0.31)
			(layers "F.Cu" "F.Mask" "F.Paste")
			(roundrect_rratio 0.25)
			(net 90 "/Ethernet/VSS")
			(pinfunction "VSSA")
			(pintype "power_in")
		)
		(pad "5" smd roundrect
			(at -2.327 1.3 270)
			(size 0.75 0.31)
			(layers "F.Cu" "F.Mask" "F.Paste")
			(roundrect_rratio 0.25)
			(net 90 "/Ethernet/VSS")
			(pinfunction "VSSB")
			(pintype "power_in")
		)
		(pad "6" smd roundrect
			(at -1.301 2.325 270)
			(size 0.31 0.75)
			(layers "F.Cu" "F.Mask" "F.Paste")
			(roundrect_rratio 0.25)
			(net 360 "/Ethernet/CLSB")
			(pinfunction "CLSB")
			(pintype "input")
		)
		(pad "7" smd roundrect
			(at -0.652 2.325 270)
			(size 0.31 0.75)
			(layers "F.Cu" "F.Mask" "F.Paste")
			(roundrect_rratio 0.25)
			(net 357 "/Ethernet/REF")
			(pinfunction "REF")
			(pintype "input")
		)
		(pad "8" smd roundrect
			(at 0 2.325 270)
			(size 0.31 0.75)
			(layers "F.Cu" "F.Mask" "F.Paste")
			(roundrect_rratio 0.25)
			(net 356 "/Ethernet/AMPS_CTL")
			(pinfunction "AMPS_CTL")
			(pintype "input")
		)
		(pad "9" smd roundrect
			(at 0.65 2.325 270)
			(size 0.31 0.75)
			(layers "F.Cu" "F.Mask" "F.Paste")
			(roundrect_rratio 0.25)
			(net 358 "/Ethernet/MPS_DUTY")
			(pinfunction "MPS_DUTY")
			(pintype "input")
		)
		(pad "10" smd roundrect
			(at 1.3 2.325 270)
			(size 0.31 0.75)
			(layers "F.Cu" "F.Mask" "F.Paste")
			(roundrect_rratio 0.25)
			(net 393 "unconnected-(U401-~{AUTCLS}-Pad10)")
			(pinfunction "~{AUTCLS}")
			(pintype "input+no_connect")
		)
		(pad "11" smd roundrect
			(at 2.325 1.3 270)
			(size 0.75 0.31)
			(layers "F.Cu" "F.Mask" "F.Paste")
			(roundrect_rratio 0.25)
			(net 1 "GNDD")
			(pinfunction "RTNA")
			(pintype "power_out")
		)
		(pad "12" smd roundrect
			(at 2.325 0.65 270)
			(size 0.75 0.31)
			(layers "F.Cu" "F.Mask" "F.Paste")
			(roundrect_rratio 0.25)
			(net 1 "GNDD")
			(pinfunction "RTNB")
			(pintype "power_out")
		)
		(pad "13" smd roundrect
			(at 2.325 0 270)
			(size 0.75 0.31)
			(layers "F.Cu" "F.Mask" "F.Paste")
			(roundrect_rratio 0.25)
			(net 363 "/Ethernet/PG")
			(pinfunction "PG")
			(pintype "output")
		)
		(pad "14" smd roundrect
			(at 2.325 -0.652 270)
			(size 0.75 0.31)
			(layers "F.Cu" "F.Mask" "F.Paste")
			(roundrect_rratio 0.25)
			(net 394 "unconnected-(U401-NC-Pad14)")
			(pinfunction "NC")
			(pintype "no_connect")
		)
		(pad "15" smd roundrect
			(at 2.325 -1.301 270)
			(size 0.75 0.31)
			(layers "F.Cu" "F.Mask" "F.Paste")
			(roundrect_rratio 0.25)
			(net 395 "unconnected-(U401-NC-Pad15)")
			(pinfunction "NC")
			(pintype "no_connect")
		)
		(pad "16" smd roundrect
			(at 1.3 -2.327 270)
			(size 0.31 0.75)
			(layers "F.Cu" "F.Mask" "F.Paste")
			(roundrect_rratio 0.25)
			(net 396 "unconnected-(U401-IRSHDL_EN-Pad16)")
			(pinfunction "IRSHDL_EN")
			(pintype "output+no_connect")
		)
		(pad "17" smd roundrect
			(at 0.65 -2.327 270)
			(size 0.31 0.75)
			(layers "F.Cu" "F.Mask" "F.Paste")
			(roundrect_rratio 0.25)
			(net 364 "/Ethernet/TPL")
			(pinfunction "TPL")
			(pintype "output")
		)
		(pad "18" smd roundrect
			(at 0 -2.327 270)
			(size 0.31 0.75)
			(layers "F.Cu" "F.Mask" "F.Paste")
			(roundrect_rratio 0.25)
			(net 362 "/Ethernet/TPH")
			(pinfunction "TPH")
			(pintype "output")
		)
		(pad "19" smd roundrect
			(at -0.652 -2.327 270)
			(size 0.31 0.75)
			(layers "F.Cu" "F.Mask" "F.Paste")
			(roundrect_rratio 0.25)
			(net 365 "/Ethernet/~{BT}")
			(pinfunction "~{BT}")
			(pintype "output")
		)
		(pad "20" smd roundrect
			(at -1.301 -2.327 270)
			(size 0.31 0.75)
			(layers "F.Cu" "F.Mask" "F.Paste")
			(roundrect_rratio 0.25)
			(net 397 "unconnected-(U401-NC-Pad20)")
			(pinfunction "NC")
			(pintype "no_connect")
		)
		(pad "21" smd rect
			(at 0 0 270)
			(size 2.2 2.2)
			(layers "F.Cu" "F.Mask")
			(net 90 "/Ethernet/VSS")
			(pinfunction "PAD_VSSC")
			(pintype "power_in")
		)
	)
)
